# T6G (Grand Teton) — schematic netlist excerpt (pin names and nets, part order shuffled) for the footprints in the layout excerpt that follows; sources: Cadence DE-HDL packaged netlist, KiCad conversion of 04192023_DAF0TMB3IC0_F0TG_MB_C_brd_V02_OCP.brd

U268  GL852GOHY60  GL852G-OHY60 IC  pkg QFN28_THXL  page 234
  DM0  = USB2_P0_R_DN
  DP0  = USB2_P0_R_DP
  DM1  = USB2_HUB_SWB_DN
  DP1  = USB2_HUB_SWB_DP
  AVDD(0)  = P3V3_AUX_USB_HUB
  DM2  = NC_USB_HUB_DM2
  DP2  = NC_USB_HUB_DP2
  RREF  = USB_HUB_RREF
  AVDD(1)  = P3V3_AUX_USB_HUB
  X1  = USB_HUB_XTAL_IN
  X2  = USB_HUB_XTAL_OUT
  DM3  = NC_USB_HUB_DM3
  DP3  = NC_USB_HUB_DP3
  AVDD(2)  = P3V3_AUX_USB_HUB
  DM4  = NC_USB_HUB_DM4
  DP4  = NC_USB_HUB_DP4
  \reset#\  = RST_USB_HUB_R_N
  \test||scl\  = USB_HUB_TEST
  \ovcur4#\  = USB_HUB_OVCUR4
  \ovcur3#\  = USB_HUB_OVCUR3
  DVDD  = USB_HUB_DVDD
  PSELF  = USB_HUB_PSELF
  PGANG  = USB_HUB_PGANG
  \ovcur2#||smd\  = USB_HUB_OVCUR2
  \ovcur1#||smc\  = USB_HUB_OVCUR1
  SDA  = NC_USB_HUB_SDA
  V5  = P3V3_AUX_USB_HUB
  V33  = P3V3_AUX_USB_HUB
  TH  = GND

(kicad_pcb
	(version 20260206)
	(generator "pcbnew")
	(generator_version "10.0")
	(general
		(thickness 1.6)
		(legacy_teardrops no)
	)
	(paper "A4")
	(title_block
		(title "04192023_DAF0TMB3IC0_F0TG_MB_C_brd_V02_OCP.brd")
		(comment 1 "Grand Teton / footprint 3886 of 8354 (U268), pads 1-29 of 29")
	)
	(layers
		(0 "F.Cu" signal "TOP")
		(4 "In1.Cu" signal "GND")
		(6 "In2.Cu" signal "IN1")
		(8 "In3.Cu" signal "GND1")
		(10 "In4.Cu" signal "IN2")
		(12 "In5.Cu" signal "GND2")
		(14 "In6.Cu" signal "IN3")
		(16 "In7.Cu" signal "GND3")
		(18 "In8.Cu" signal "VCC")
		(20 "In9.Cu" signal "VCC1")
		(22 "In10.Cu" signal "GND4")
		(24 "In11.Cu" signal "IN4")
		(26 "In12.Cu" signal "GND5")
		(28 "In13.Cu" signal "IN5")
		(30 "In14.Cu" signal "GND6")
		(32 "In15.Cu" signal "IN6")
		(34 "In16.Cu" signal "GND7")
		(2 "B.Cu" signal "BOTTOM")
		(9 "F.Adhes" user "F.Adhesive")
		(11 "B.Adhes" user "B.Adhesive")
		(13 "F.Paste" user "Package Geometry/Pastemask Top")
		(15 "B.Paste" user "Package Geometry/Pastemask Bottom")
		(5 "F.SilkS" user "Ref Des/Silkscreen Top")
		(7 "B.SilkS" user "Ref Des/Silkscreen Bottom")
		(1 "F.Mask" user "Board Geometry/Soldermask Top")
		(3 "B.Mask" user "Board Geometry/Soldermask Bottom")
		(17 "Dwgs.User" user "User.Drawings")
		(19 "Cmts.User" user "User.Comments")
		(21 "Eco1.User" user "User.Eco1")
		(23 "Eco2.User" user "User.Eco2")
		(25 "Edge.Cuts" user "Board Geometry/Outline")
		(27 "Margin" user)
		(31 "F.CrtYd" user "Package Geometry/Place Bound Top")
		(29 "B.CrtYd" user "Package Geometry/Place Bound Bottom")
		(35 "F.Fab" user "Ref Des/Assembly Top")
		(33 "B.Fab" user "Ref Des/Assembly Bottom")
	)
	(footprint ""
		(layer "F.Cu")
		(at 14.064996 -99.136454 -90)
		(property "Reference" "U268"
			(at -3.448304 -3.957828 0)
			(unlocked yes)
			(layer "F.SilkS")
			(effects
				(font
					(size 0.7874 0.5842)
					(thickness 0.1524)
				)
				(justify left)
			)
		)
		(property "Value" ""
			(at 0 0 270)
			(layer "F.Fab")
			(effects
				(font
					(size 1.27 1.27)
				)
			)
		)
		(duplicate_pad_numbers_are_jumpers no)
		(pad "1" smd rect
			(at -2.412492 -1.500124)
			(size 0.254 0.7366)
			(layers "F.Cu" "F.Mask" "F.Paste")
			(net "USB2_P0_R_DN")
		)
		(pad "2" smd rect
			(at -2.412492 -0.999998)
			(size 0.254 0.7366)
			(layers "F.Cu" "F.Mask" "F.Paste")
			(net "USB2_P0_R_DP")
		)
		(pad "3" smd rect
			(at -2.412492 -0.499872)
			(size 0.254 0.7366)
			(layers "F.Cu" "F.Mask" "F.Paste")
			(net "USB2_HUB_SWB_DN")
		)
		(pad "4" smd rect
			(at -2.412492 0)
			(size 0.254 0.7366)
			(layers "F.Cu" "F.Mask" "F.Paste")
			(net "USB2_HUB_SWB_DP")
		)
		(pad "5" smd rect
			(at -2.412492 0.499872)
			(size 0.254 0.7366)
			(layers "F.Cu" "F.Mask" "F.Paste")
			(net "P3V3_AUX_USB_HUB")
		)
		(pad "6" smd rect
			(at -2.412492 0.999998)
			(size 0.254 0.7366)
			(layers "F.Cu" "F.Mask" "F.Paste")
			(net "NC_USB_HUB_DM2")
		)
		(pad "7" smd rect
			(at -2.412492 1.500124)
			(size 0.254 0.7366)
			(layers "F.Cu" "F.Mask" "F.Paste")
			(net "NC_USB_HUB_DP2")
		)
		(pad "8" smd rect
			(at -1.500124 2.412492 270)
			(size 0.254 0.7366)
			(layers "F.Cu" "F.Mask" "F.Paste")
			(net "USB_HUB_RREF")
		)
		(pad "9" smd rect
			(at -0.999998 2.412492 270)
			(size 0.254 0.7366)
			(layers "F.Cu" "F.Mask" "F.Paste")
			(net "P3V3_AUX_USB_HUB")
		)
		(pad "10" smd rect
			(at -0.499872 2.412492 270)
			(size 0.254 0.7366)
			(layers "F.Cu" "F.Mask" "F.Paste")
			(net "USB_HUB_XTAL_IN")
		)
		(pad "11" smd rect
			(at 0 2.412492 270)
			(size 0.254 0.7366)
			(layers "F.Cu" "F.Mask" "F.Paste")
			(net "USB_HUB_XTAL_OUT")
		)
		(pad "12" smd rect
			(at 0.499872 2.412492 270)
			(size 0.254 0.7366)
			(layers "F.Cu" "F.Mask" "F.Paste")
			(net "NC_USB_HUB_DM3")
		)
		(pad "13" smd rect
			(at 0.999998 2.412492 270)
			(size 0.254 0.7366)
			(layers "F.Cu" "F.Mask" "F.Paste")
			(net "NC_USB_HUB_DP3")
		)
		(pad "14" smd rect
			(at 1.500124 2.412492 270)
			(size 0.254 0.7366)
			(layers "F.Cu" "F.Mask" "F.Paste")
			(net "P3V3_AUX_USB_HUB")
		)
		(pad "15" smd rect
			(at 2.412492 1.500124)
			(size 0.254 0.7366)
			(layers "F.Cu" "F.Mask" "F.Paste")
			(net "NC_USB_HUB_DM4")
		)
		(pad "16" smd rect
			(at 2.412492 0.999998)
			(size 0.254 0.7366)
			(layers "F.Cu" "F.Mask" "F.Paste")
			(net "NC_USB_HUB_DP4")
		)
		(pad "17" smd rect
			(at 2.412492 0.499872)
			(size 0.254 0.7366)
			(layers "F.Cu" "F.Mask" "F.Paste")
			(net "RST_USB_HUB_R_N")
		)
		(pad "18" smd rect
			(at 2.412492 0)
			(size 0.254 0.7366)
			(layers "F.Cu" "F.Mask" "F.Paste")
			(net "USB_HUB_TEST")
		)
		(pad "19" smd rect
			(at 2.412492 -0.499872)
			(size 0.254 0.7366)
			(layers "F.Cu" "F.Mask" "F.Paste")
			(net "USB_HUB_OVCUR4")
		)
		(pad "20" smd rect
			(at 2.412492 -0.999998)
			(size 0.254 0.7366)
			(layers "F.Cu" "F.Mask" "F.Paste")
			(net "USB_HUB_OVCUR3")
		)
		(pad "21" smd rect
			(at 2.412492 -1.500124)
			(size 0.254 0.7366)
			(layers "F.Cu" "F.Mask" "F.Paste")
			(net "USB_HUB_DVDD")
		)
		(pad "22" smd rect
			(at 1.500124 -2.412492 270)
			(size 0.254 0.7366)
			(layers "F.Cu" "F.Mask" "F.Paste")
			(net "USB_HUB_PSELF")
		)
		(pad "23" smd rect
			(at 0.999998 -2.412492 270)
			(size 0.254 0.7366)
			(layers "F.Cu" "F.Mask" "F.Paste")
			(net "USB_HUB_PGANG")
		)
		(pad "24" smd rect
			(at 0.499872 -2.412492 270)
			(size 0.254 0.7366)
			(layers "F.Cu" "F.Mask" "F.Paste")
			(net "USB_HUB_OVCUR2")
		)
		(pad "25" smd rect
			(at 0 -2.412492 270)
			(size 0.254 0.7366)
			(layers "F.Cu" "F.Mask" "F.Paste")
			(net "USB_HUB_OVCUR1")
		)
		(pad "26" smd rect
			(at -0.499872 -2.412492 270)
			(size 0.254 0.7366)
			(layers "F.Cu" "F.Mask" "F.Paste")
			(net "NC_USB_HUB_SDA")
		)
		(pad "27" smd rect
			(at -0.999998 -2.412492 270)
			(size 0.254 0.7366)
			(layers "F.Cu" "F.Mask" "F.Paste")
			(net "P3V3_AUX_USB_HUB")
		)
		(pad "28" smd rect
			(at -1.500124 -2.412492 270)
			(size 0.254 0.7366)
			(layers "F.Cu" "F.Mask" "F.Paste")
			(net "P3V3_AUX_USB_HUB")
		)
		(pad "TH" smd rect
			(at 0 0 270)
			(size 3.556 3.556)
			(layers "F.Cu" "F.Mask" "F.Paste")
			(net "GND")
		)
	)
)
